FILE_TYPE = CONNECTIVITY;
{Allegro Design Entry HDL 16.6-p007 (v16-6-112F) 10/10/2012}
"PAGE_NUMBER" = 220;
0"NC";
1"PVDDQ_DEF\g";
2"GND\g";
3"VR_FET_SW_P12V_STBY_PVDDQ_DEF\g";
4"GND\g";
5"P12V_STBY\g";
6"GND\g";
7"PVDDQ_DEF\g";
8"PVDDQ_DEF\g";
9"GND\g";
10"PVDDQ_DEF\g";
11"GND\g";
12"PVDDQ_DEF\g";
13"GND\g";
14"PVDDQ_DEF\g";
15"GND\g";
16"GND\g";
17"PVDDQ_DEF\g";
18"PVDDQ_DEF\g";
19"GND\g";
20"PVDDQ_DEF\g";
21"GND\g";
22"VSENSE_PVDDQ_DEF_P";
23"VSENSE_PVDDQ_DEF_N";
%"PVDDQ_DEF"
"1","(2675,1950)","0","mstr_symbols","I109";
;
ROOM"VDDQ_DEF_PWR_VR"
BOM_COST"MEM_VRD_PVDDQ_DEF"
BODY_TYPE"PLUMBING"
CDS_LIB"mstr_symbols"
HDL_POWER"PVDDQ_DEF"
VOLTAGE"1.2V";
"G\NAC"1;
%"CAP"
"1","(2400,2825)","0","mstr_discrete","I110";
;
CDS_SEC"1"
ROOM"VDDQ_DEF_PWR_VR"
CDS_LOCATION"C5A10"
SEC"1"
BOM_COST"MEM_VRD_PVDDQ_DEF"
SEC_TYPE"0805"
CDS_LIB"mstr_discrete"
LOCATION"C5A10"
PART_NUMBER"602433-112"
VALUE"100UF"
PACK_TYPE"0805"
VOLTAGE"4V"
TOLERANCE"20%"
MATERIAL"X5R";
"A"
$PN"1"20;
"B"
$PN"2"21;
%"GND"
"1","(4400,1300)","0","mstr_symbols","I114";
;
HDL_POWER"GND"
VOLTAGE"0"
CDS_LIB"mstr_symbols"
SIZE"1B"
BODY_TYPE"PLUMBING"
ROOM"VDDQ_DEF_PWR_VR"
BOM_COST"MEM_VRD_PVDDQ_DEF";
"A\NAC"2;
%"VCC_CORE"
"1","(-1050,1375)","0","mstr_symbols","I120";
;
CDS_LIB"mstr_symbols"
HDL_POWER"VR_FET_SW_P12V_STBY_PVDDQ_DEF";
"A"3;
%"GND"
"1","(-1050,700)","0","mstr_symbols","I123";
;
SIZE"1B"
HDL_POWER"GND"
VOLTAGE"0"
CDS_LIB"mstr_symbols"
BODY_TYPE"PLUMBING"
BOM_COST"MEM_VRD_PVDDQ_DEF"
ROOM"VDDQ_DEF_PWR_VR";
"A\NAC"4;
%"INDUCTOR"
"1","(-1475,1125)","0","mstr_discrete","I124";
;
CDS_SEC"1"
CDS_LIB"mstr_discrete"
SEC"1"
SEC_TYPE"SM"
ROOM"VDDQ_DEF_PWR_VR"
BOM_COST"MEM_VRD_PVDDQ_DEF"
CDS_LOCATION"L7A5"
PACK_TYPE"SM"
MATERIAL"IND"
LOCATION"L7A5"
PART_NUMBER"D92183-020"
VALUE"100NH";
"INA\NAC"
$PN"1"5;
"INB\NAC"
$PN"2"3;
%"CAPP"
"1","(-1050,925)","0","mstr_discrete","I175";
;
CDS_SEC"1"
ROOM"VDDQ_DEF_PWR_VR"
SEC_TYPE"2626"
SEC"1"
CDS_LOCATION"C7A19"
CDS_LIB"mstr_discrete"
LOCATION"C7A19"
PART_NUMBER"A31228-047"
VALUE"270UF"
TOLERANCE"20%"
PACK_TYPE"2626"
VOLTAGE"16V"
MATERIAL"OSCON";
"B"
$PN"2"4;
"A"
$PN"1"3;
%"P12V_STBY"
"1","(-1700,1425)","0","mstr_symbols","I176";
;
VOLTAGE"12.0V"
SIZE"1B"
CDS_LIB"mstr_symbols"
BODY_TYPE"PLUMBING"
HDL_POWER"P12V_STBY";
"G\NAC"5;
%"CAP"
"1","(-2225,2900)","0","mstr_discrete","I177";
;
CDS_SEC"1"
SEC"1"
SEC_TYPE"0805LF"
ROOM"VDDQ_DEF_CPU0"
BOM_COST"MEM_VRD_PVDDQ_DEF"
VOLTAGE"4V"
CDS_LOCATION"C5P2"
CDS_LIB"mstr_discrete"
PART_NUMBER"C95333-002"
PACK_TYPE"0805LF"
VALUE"22UF"
TOLERANCE"20%"
LOCATION"C5P2"
MATERIAL"X6S";
"A"
$PN"1"7;
"B"
$PN"2"11;
%"CAP"
"1","(-1875,2900)","0","mstr_discrete","I179";
;
CDS_SEC"1"
SEC_TYPE"0805LF"
SEC"1"
ROOM"VDDQ_DEF_CPU0"
BOM_COST"MEM_VRD_PVDDQ_DEF"
CDS_LOCATION"C5P1"
CDS_LIB"mstr_discrete"
VOLTAGE"4V"
PART_NUMBER"C95333-002"
LOCATION"C5P1"
VALUE"22UF"
MATERIAL"X6S"
PACK_TYPE"0805LF"
TOLERANCE"20%";
"A"
$PN"1"7;
"B"
$PN"2"11;
%"CAP"
"1","(-1475,2900)","0","mstr_discrete","I180";
;
CDS_SEC"1"
SEC"1"
SEC_TYPE"0603LF"
ROOM"VDDQ_DEF_CPU0"
BOM_COST"MEM_VRD_PVDDQ_DEF"
CDS_LOCATION"C5D9"
CDS_LIB"mstr_discrete"
PACK_TYPE"0603LF"
PART_NUMBER"E15431-001"
VOLTAGE"4V"
TOLERANCE"20%"
VALUE"10UF"
LOCATION"C5D9"
MATERIAL"X6S";
"A"
$PN"1"10;
"B"
$PN"2"6;
%"GND"
"1","(-425,2550)","0","mstr_symbols","I181";
;
HDL_POWER"GND"
VOLTAGE"0"
CDS_LIB"mstr_symbols"
SIZE"1B"
BODY_TYPE"PLUMBING"
BOM_COST"MEM_VRD_PVDDQ_CD"
ROOM"VDDQ_ABC_PWR_VR";
"A\NAC"6;
%"CAP"
"1","(-1125,2900)","0","mstr_discrete","I182";
;
CDS_SEC"1"
SEC_TYPE"0603LF"
SEC"1"
ROOM"VDDQ_DEF_CPU0"
BOM_COST"MEM_VRD_PVDDQ_DEF"
CDS_LOCATION"C5D6"
CDS_LIB"mstr_discrete"
VALUE"10UF"
LOCATION"C5D6"
PART_NUMBER"E15431-001"
TOLERANCE"20%"
PACK_TYPE"0603LF"
VOLTAGE"4V"
MATERIAL"X6S";
"A"
$PN"1"10;
"B"
$PN"2"6;
%"CAP"
"1","(-775,2900)","0","mstr_discrete","I183";
;
CDS_SEC"1"
SEC_TYPE"0603LF"
SEC"1"
ROOM"VDDQ_DEF_CPU0"
BOM_COST"MEM_VRD_PVDDQ_DEF"
CDS_LOCATION"C5D7"
CDS_LIB"mstr_discrete"
PART_NUMBER"E15431-001"
TOLERANCE"20%"
PACK_TYPE"0603LF"
VOLTAGE"4V"
MATERIAL"X6S"
VALUE"10UF"
LOCATION"C5D7";
"A"
$PN"1"10;
"B"
$PN"2"6;
%"CAP"
"1","(-425,2900)","0","mstr_discrete","I184";
;
CDS_SEC"1"
SEC_TYPE"0603LF"
SEC"1"
ROOM"VDDQ_DEF_CPU0"
BOM_COST"MEM_VRD_PVDDQ_DEF"
CDS_LIB"mstr_discrete"
CDS_LOCATION"C5D8"
PART_NUMBER"E15431-001"
PACK_TYPE"0603LF"
LOCATION"C5D8"
VALUE"10UF"
VOLTAGE"4V"
TOLERANCE"20%"
MATERIAL"X6S";
"A"
$PN"1"10;
"B"
$PN"2"6;
%"PVDDQ_DEF"
"1","(-2225,3175)","0","mstr_symbols","I185";
;
ROOM"VDDQ_DEF_PWR_VR"
BOM_COST"MEM_VRD_PVPP_DEF"
BODY_TYPE"PLUMBING"
CDS_LIB"mstr_symbols"
HDL_POWER"PVDDQ_DEF"
VOLTAGE"1.2V";
"G\NAC"7;
%"PVDDQ_DEF"
"1","(2650,1225)","0","mstr_symbols","I189";
;
ROOM"VDDQ_DEF_PWR_VR"
BOM_COST"MEM_VRD_PVDDQ_DEF"
HDL_POWER"PVDDQ_DEF"
VOLTAGE"1.2V"
BODY_TYPE"PLUMBING"
CDS_LIB"mstr_symbols";
"G\NAC"8;
%"GND"
"1","(3600,600)","0","mstr_symbols","I191";
;
CDS_LIB"mstr_symbols"
SIZE"1B"
HDL_POWER"GND"
VOLTAGE"0"
BODY_TYPE"PLUMBING"
BOM_COST"MEM_VRD_PVDDQ_DEF"
ROOM"VDDQ_DEF_PWR_VR";
"A\NAC"9;
%"CAP_A"
"1","(2650,950)","0","dev_discrete","I192";
;
CDS_LOCATION"C5L15"
CDS_SEC"1"
SEC_TYPE"0603V"
SEC"1"
CDS_LIB"dev_discrete"
LOCATION"C5L15"
VALUE"47UF"
PART_NUMBER"602433-106"
PACK_TYPE"0603V"
TOLERANCE"20%"
VOLTAGE"4V"
MATERIAL"X5R";
"B"
$PN"2"9;
"A"
$PN"1"8;
%"CAP_A"
"1","(3000,950)","0","dev_discrete","I193";
;
CDS_LOCATION"C5A5"
CDS_SEC"1"
SEC_TYPE"0603V"
SEC"1"
CDS_LIB"dev_discrete"
LOCATION"C5A5"
PART_NUMBER"602433-106"
VALUE"47UF"
TOLERANCE"20%"
PACK_TYPE"0603V"
VOLTAGE"4V"
MATERIAL"X5R";
"B"
$PN"2"9;
"A"
$PN"1"8;
%"CAP_A"
"1","(3400,950)","0","dev_discrete","I194";
;
CDS_LOCATION"C5B1"
CDS_SEC"1"
SEC_TYPE"0603V"
SEC"1"
CDS_LIB"dev_discrete"
LOCATION"C5B1"
VALUE"47UF"
PART_NUMBER"602433-106"
PACK_TYPE"0603V"
MATERIAL"X5R"
VOLTAGE"4V"
TOLERANCE"20%";
"B"
$PN"2"9;
"A"
$PN"1"8;
%"CAP_A"
"1","(4125,1675)","0","dev_discrete","I195";
;
SEC"1"
SEC_TYPE"0603V"
CDS_SEC"1"
CDS_LOCATION"C5M9"
CDS_LIB"dev_discrete"
LOCATION"C5M9"
MATERIAL"X5R"
VOLTAGE"4V"
TOLERANCE"20%"
VALUE"47UF"
PART_NUMBER"602433-106"
PACK_TYPE"0603V";
"B"
$PN"2"2;
"A"
$PN"1"1;
%"CAP_A"
"1","(3775,1675)","0","dev_discrete","I196";
;
SEC"1"
SEC_TYPE"0603V"
CDS_SEC"1"
CDS_LOCATION"C4M5"
CDS_LIB"dev_discrete"
PART_NUMBER"602433-106"
LOCATION"C4M5"
VALUE"47UF"
TOLERANCE"20%"
VOLTAGE"4V"
MATERIAL"X5R"
PACK_TYPE"0603V";
"B"
$PN"2"2;
"A"
$PN"1"1;
%"CAP_A"
"1","(2675,1675)","0","dev_discrete","I197";
;
SEC"1"
SEC_TYPE"0603V"
CDS_SEC"1"
CDS_LOCATION"C5B2"
CDS_LIB"dev_discrete"
LOCATION"C5B2"
VALUE"47UF"
TOLERANCE"20%"
MATERIAL"X5R"
VOLTAGE"4V"
PART_NUMBER"602433-106"
PACK_TYPE"0603V";
"B"
$PN"2"2;
"A"
$PN"1"1;
%"CAP_A"
"1","(3025,1675)","0","dev_discrete","I198";
;
CDS_LOCATION"C5M10"
CDS_SEC"1"
SEC_TYPE"0603V"
SEC"1"
CDS_LIB"dev_discrete"
LOCATION"C5M10"
VALUE"47UF"
TOLERANCE"20%"
VOLTAGE"4V"
MATERIAL"X5R"
PART_NUMBER"602433-106"
PACK_TYPE"0603V";
"B"
$PN"2"2;
"A"
$PN"1"1;
%"CAP_A"
"1","(3425,1675)","0","dev_discrete","I199";
;
CDS_SEC"1"
SEC_TYPE"0603V"
SEC"1"
CDS_LOCATION"C5M3"
CDS_LIB"dev_discrete"
LOCATION"C5M3"
PART_NUMBER"602433-106"
VALUE"47UF"
PACK_TYPE"0603V"
MATERIAL"X5R"
VOLTAGE"4V"
TOLERANCE"20%";
"B"
$PN"2"2;
"A"
$PN"1"1;
%"CAP_A"
"1","(4525,1675)","0","dev_discrete","I200";
;
SEC"1"
CDS_SEC"1"
SEC_TYPE"0603V"
CDS_LOCATION"C5M11"
CDS_LIB"dev_discrete"
LOCATION"C5M11"
PART_NUMBER"602433-106"
VALUE"47UF"
TOLERANCE"20%"
PACK_TYPE"0603V"
VOLTAGE"4V"
MATERIAL"X5R";
"B"
$PN"2"2;
"A"
$PN"1"1;
%"PVDDQ_DEF"
"1","(-1475,3175)","0","mstr_symbols","I201";
;
ROOM"VDDQ_DEF_PWR_VR"
HDL_POWER"PVDDQ_DEF"
BOM_COST"MEM_VRD_PVPP_DEF"
CDS_LIB"mstr_symbols"
VOLTAGE"1.2V"
BODY_TYPE"PLUMBING";
"G\NAC"10;
%"GND"
"1","(-1875,2525)","0","mstr_symbols","I202";
;
HDL_POWER"GND"
VOLTAGE"0"
CDS_LIB"mstr_symbols"
SIZE"1B"
BODY_TYPE"PLUMBING"
BOM_COST"MEM_VRD_PVDDQ_CD"
ROOM"VDDQ_ABC_PWR_VR";
"A\NAC"11;
%"CAP_A"
"1","(2225,100)","0","dev_discrete","I203";
;
$SEC"1"
CDS_SEC"1"
ROOM"PVDDQ_DEF"
CDS_LIB"dev_discrete"
CDS_LOCATION"C5A19"
LOCATION"C5A19"
VALUE"22.0UF"
TOLERANCE"20%"
VOLTAGE"4V"
MATERIAL"X6S"
PART_NUMBER"E15431-004"
PACK_TYPE"0603V";
"B"
$PN"2"13;
"A"
$PN"1"12;
%"CAP_A"
"1","(1950,100)","0","dev_discrete","I204";
;
$SEC"1"
CDS_SEC"1"
ROOM"PVDDQ_DEF"
CDS_LIB"dev_discrete"
CDS_LOCATION"C5A18"
LOCATION"C5A18"
VALUE"22.0UF"
TOLERANCE"20%"
VOLTAGE"4V"
MATERIAL"X6S"
PART_NUMBER"E15431-004"
PACK_TYPE"0603V";
"B"
$PN"2"13;
"A"
$PN"1"12;
%"CAP_A"
"1","(1650,100)","0","dev_discrete","I205";
;
$SEC"1"
CDS_SEC"1"
ROOM"PVDDQ_DEF"
CDS_LOCATION"C5A17"
CDS_LIB"dev_discrete"
LOCATION"C5A17"
VALUE"22.0UF"
TOLERANCE"20%"
VOLTAGE"4V"
MATERIAL"X6S"
PACK_TYPE"0603V"
PART_NUMBER"E15431-004";
"B"
$PN"2"13;
"A"
$PN"1"12;
%"CAP_A"
"1","(1350,100)","0","dev_discrete","I206";
;
SEC"1"
SEC_TYPE"0603V"
ROOM"PVDDQ_DEF"
CDS_SEC"1"
CDS_LOCATION"C5A4"
CDS_LIB"dev_discrete"
VALUE"22.0UF"
LOCATION"C5A4"
TOLERANCE"20%"
VOLTAGE"4V"
MATERIAL"X6S"
PART_NUMBER"E15431-004"
PACK_TYPE"0603V";
"B"
$PN"2"13;
"A"
$PN"1"12;
%"CAP_A"
"1","(1075,100)","0","dev_discrete","I207";
;
$SEC"1"
CDS_SEC"1"
ROOM"PVDDQ_DEF"
CDS_LOCATION"C5A16"
CDS_LIB"dev_discrete"
VALUE"22.0UF"
LOCATION"C5A16"
TOLERANCE"20%"
VOLTAGE"4V"
MATERIAL"X6S"
PART_NUMBER"E15431-004"
PACK_TYPE"0603V";
"B"
$PN"2"13;
"A"
$PN"1"12;
%"CAP_A"
"1","(800,100)","0","dev_discrete","I208";
;
$SEC"1"
CDS_SEC"1"
ROOM"PVDDQ_DEF"
CDS_LIB"dev_discrete"
CDS_LOCATION"C5A9"
VALUE"22.0UF"
VOLTAGE"4V"
TOLERANCE"20%"
LOCATION"C5A9"
MATERIAL"X6S"
PART_NUMBER"E15431-004"
PACK_TYPE"0603V";
"B"
$PN"2"13;
"A"
$PN"1"12;
%"CAP_A"
"1","(500,100)","0","dev_discrete","I209";
;
ROOM"PVDDQ_DEF"
CDS_LOCATION"C5A8"
CDS_SEC"1"
$SEC"1"
CDS_LIB"dev_discrete"
LOCATION"C5A8"
VALUE"22.0UF"
TOLERANCE"20%"
VOLTAGE"4V"
MATERIAL"X6S"
PART_NUMBER"E15431-004"
PACK_TYPE"0603V";
"B"
$PN"2"13;
"A"
$PN"1"12;
%"CAP_A"
"1","(200,100)","0","dev_discrete","I210";
;
SEC"1"
SEC_TYPE"0603V"
ROOM"PVDDQ_DEF"
CDS_SEC"1"
CDS_LIB"dev_discrete"
CDS_LOCATION"C5A3"
LOCATION"C5A3"
VALUE"22.0UF"
TOLERANCE"20%"
VOLTAGE"4V"
MATERIAL"X6S"
PART_NUMBER"E15431-004"
PACK_TYPE"0603V";
"B"
$PN"2"13;
"A"
$PN"1"12;
%"CAP_A"
"1","(-125,100)","0","dev_discrete","I211";
;
$SEC"1"
CDS_SEC"1"
ROOM"PVDDQ_DEF"
CDS_LIB"dev_discrete"
CDS_LOCATION"C5A7"
LOCATION"C5A7"
PART_NUMBER"E15431-004"
VALUE"22.0UF"
TOLERANCE"20%"
PACK_TYPE"0603V"
MATERIAL"X6S"
VOLTAGE"4V";
"B"
$PN"2"13;
"A"
$PN"1"12;
%"CAP_A"
"1","(-400,100)","0","dev_discrete","I212";
;
$SEC"1"
CDS_SEC"1"
ROOM"PVDDQ_DEF"
CDS_LOCATION"C5A6"
CDS_LIB"dev_discrete"
LOCATION"C5A6"
VALUE"22.0UF"
TOLERANCE"20%"
VOLTAGE"4V"
MATERIAL"X6S"
PACK_TYPE"0603V"
PART_NUMBER"E15431-004";
"B"
$PN"2"13;
"A"
$PN"1"12;
%"CAP_A"
"1","(-700,100)","0","dev_discrete","I213";
;
$SEC"1"
CDS_SEC"1"
ROOM"PVDDQ_DEF"
CDS_LOCATION"C5A14"
CDS_LIB"dev_discrete"
LOCATION"C5A14"
VALUE"22.0UF"
TOLERANCE"20%"
VOLTAGE"4V"
MATERIAL"X6S"
PART_NUMBER"E15431-004"
PACK_TYPE"0603V";
"B"
$PN"2"13;
"A"
$PN"1"12;
%"CAP_A"
"1","(-1000,100)","0","dev_discrete","I214";
;
SEC"1"
SEC_TYPE"0603V"
ROOM"PVDDQ_DEF"
CDS_SEC"1"
CDS_LOCATION"C5A2"
CDS_LIB"dev_discrete"
LOCATION"C5A2"
VALUE"22.0UF"
TOLERANCE"20%"
VOLTAGE"4V"
MATERIAL"X6S"
PART_NUMBER"E15431-004"
PACK_TYPE"0603V";
"B"
$PN"2"13;
"A"
$PN"1"12;
%"CAP_A"
"1","(-1275,100)","0","dev_discrete","I215";
;
CDS_SEC"1"
$SEC"1"
ROOM"PVDDQ_DEF"
CDS_LIB"dev_discrete"
CDS_LOCATION"C5A13"
TOLERANCE"20%"
VOLTAGE"4V"
VALUE"22.0UF"
LOCATION"C5A13"
MATERIAL"X6S"
PART_NUMBER"E15431-004"
PACK_TYPE"0603V";
"B"
$PN"2"13;
"A"
$PN"1"12;
%"CAP_A"
"1","(-1550,100)","0","dev_discrete","I216";
;
$SEC"1"
CDS_SEC"1"
CDS_LOCATION"C5A12"
ROOM"PVDDQ_DEF"
CDS_LIB"dev_discrete"
VOLTAGE"4V"
TOLERANCE"20%"
VALUE"22.0UF"
LOCATION"C5A12"
MATERIAL"X6S"
PART_NUMBER"E15431-004"
PACK_TYPE"0603V";
"B"
$PN"2"13;
"A"
$PN"1"12;
%"CAP_A"
"1","(-1850,100)","0","dev_discrete","I217";
;
$SEC"1"
CDS_SEC"1"
ROOM"PVDDQ_DEF"
CDS_LIB"dev_discrete"
CDS_LOCATION"C5A15"
LOCATION"C5A15"
VALUE"22.0UF"
TOLERANCE"20%"
VOLTAGE"4V"
MATERIAL"X6S"
PART_NUMBER"E15431-004"
PACK_TYPE"0603V";
"B"
$PN"2"13;
"A"
$PN"1"12;
%"PVDDQ_DEF"
"1","(-2150,350)","0","mstr_symbols","I218";
;
VOLTAGE"1.2V"
HDL_POWER"PVDDQ_DEF"
CDS_LIB"mstr_symbols"
BODY_TYPE"PLUMBING";
"G\NAC"12;
%"CAP_A"
"1","(-2150,100)","0","dev_discrete","I219";
;
ROOM"PVDDQ_DEF"
SEC"1"
SEC_TYPE"0603V"
CDS_SEC"1"
CDS_LOCATION"C5A1"
CDS_LIB"dev_discrete"
LOCATION"C5A1"
VALUE"22.0UF"
TOLERANCE"20%"
VOLTAGE"4V"
MATERIAL"X6S"
PART_NUMBER"E15431-004"
PACK_TYPE"0603V";
"B"
$PN"2"13;
"A"
$PN"1"12;
%"GND"
"1","(-2150,-175)","0","mstr_symbols","I220";
;
HDL_POWER"GND"
VOLTAGE"0"
SIZE"1B"
CDS_LIB"mstr_symbols"
BODY_TYPE"PLUMBING"
BOM_COST"PROC_VRD_VCCIN_CPU0"
ROOM"VDDQ_ABC_PWR_VR";
"A\NAC"13;
%"CAP_A"
"1","(2225,-650)","0","dev_discrete","I221";
;
ROOM"PVDDQ_DEF"
CDS_SEC"1"
$SEC"1"
CDS_LOCATION"C5A11"
CDS_LIB"dev_discrete"
PART_NUMBER"E15431-004"
LOCATION"C5A11"
VALUE"22.0UF"
TOLERANCE"20%"
PACK_TYPE"0603V"
VOLTAGE"4V"
MATERIAL"X6S";
"B"
$PN"2"15;
"A"
$PN"1"14;
%"CAP_A"
"1","(1950,-650)","0","dev_discrete","I222";
;
$SEC"1"
CDS_SEC"1"
ROOM"PVDDQ_DEF"
CDS_LIB"dev_discrete"
CDS_LOCATION"C4M2"
LOCATION"C4M2"
PART_NUMBER"E15431-004"
VALUE"22.0UF"
TOLERANCE"20%"
PACK_TYPE"0603V"
VOLTAGE"4V"
MATERIAL"X6S";
"B"
$PN"2"15;
"A"
$PN"1"14;
%"CAP_A"
"1","(1650,-650)","0","dev_discrete","I223";
;
$SEC"1"
CDS_SEC"1"
ROOM"PVDDQ_DEF"
CDS_LIB"dev_discrete"
CDS_LOCATION"C5M1"
LOCATION"C5M1"
PART_NUMBER"E15431-004"
VALUE"22.0UF"
PACK_TYPE"0603V"
MATERIAL"X6S"
VOLTAGE"4V"
TOLERANCE"20%";
"B"
$PN"2"15;
"A"
$PN"1"14;
%"CAP_A"
"1","(1350,-650)","0","dev_discrete","I224";
;
$SEC"1"
CDS_SEC"1"
ROOM"PVDDQ_DEF"
CDS_LIB"dev_discrete"
CDS_LOCATION"C5M2"
PART_NUMBER"E15431-004"
VALUE"22.0UF"
PACK_TYPE"0603V"
MATERIAL"X6S"
VOLTAGE"4V"
TOLERANCE"20%"
LOCATION"C5M2";
"B"
$PN"2"15;
"A"
$PN"1"14;
%"CAP_A"
"1","(1075,-650)","0","dev_discrete","I225";
;
ROOM"PVDDQ_DEF"
CDS_SEC"1"
$SEC"1"
CDS_LIB"dev_discrete"
CDS_LOCATION"C5M4"
PART_NUMBER"E15431-004"
VALUE"22.0UF"
MATERIAL"X6S"
VOLTAGE"4V"
TOLERANCE"20%"
LOCATION"C5M4"
PACK_TYPE"0603V";
"B"
$PN"2"15;
"A"
$PN"1"14;
%"CAP_A"
"1","(800,-650)","0","dev_discrete","I226";
;
ROOM"PVDDQ_DEF"
CDS_SEC"1"
$SEC"1"
CDS_LIB"dev_discrete"
CDS_LOCATION"C5M5"
PART_NUMBER"E15431-004"
VALUE"22.0UF"
MATERIAL"X6S"
VOLTAGE"4V"
TOLERANCE"20%"
LOCATION"C5M5"
PACK_TYPE"0603V";
"B"
$PN"2"15;
"A"
$PN"1"14;
%"CAP_A"
"1","(500,-650)","0","dev_discrete","I227";
;
$SEC"1"
CDS_SEC"1"
ROOM"PVDDQ_DEF"
CDS_LOCATION"C5M6"
CDS_LIB"dev_discrete"
PART_NUMBER"E15431-004"
LOCATION"C5M6"
VALUE"22.0UF"
TOLERANCE"20%"
PACK_TYPE"0603V"
VOLTAGE"4V"
MATERIAL"X6S";
"B"
$PN"2"15;
"A"
$PN"1"14;
%"CAP_A"
"1","(200,-650)","0","dev_discrete","I228";
;
$SEC"1"
CDS_SEC"1"
ROOM"PVDDQ_DEF"
CDS_LOCATION"C5M7"
CDS_LIB"dev_discrete"
PART_NUMBER"E15431-004"
LOCATION"C5M7"
VALUE"22.0UF"
TOLERANCE"20%"
PACK_TYPE"0603V"
MATERIAL"X6S"
VOLTAGE"4V";
"B"
$PN"2"15;
"A"
$PN"1"14;
%"CAP_A"
"1","(-125,-650)","0","dev_discrete","I229";
;
$SEC"1"
CDS_SEC"1"
ROOM"PVDDQ_DEF"
CDS_LIB"dev_discrete"
CDS_LOCATION"C5L13"
LOCATION"C5L13"
PART_NUMBER"E15431-004"
VALUE"22.0UF"
TOLERANCE"20%"
PACK_TYPE"0603V"
MATERIAL"X6S"
VOLTAGE"4V";
"B"
$PN"2"15;
"A"
$PN"1"14;
%"CAP_A"
"1","(-400,-650)","0","dev_discrete","I230";
;
$SEC"1"
CDS_SEC"1"
ROOM"PVDDQ_DEF"
CDS_LIB"dev_discrete"
CDS_LOCATION"C5L12"
LOCATION"C5L12"
PART_NUMBER"E15431-004"
VALUE"22.0UF"
PACK_TYPE"0603V"
MATERIAL"X6S"
VOLTAGE"4V"
TOLERANCE"20%";
"B"
$PN"2"15;
"A"
$PN"1"14;
%"CAP_A"
"1","(-700,-650)","0","dev_discrete","I231";
;
$SEC"1"
CDS_SEC"1"
ROOM"PVDDQ_DEF"
CDS_LIB"dev_discrete"
CDS_LOCATION"C5L11"
LOCATION"C5L11"
PART_NUMBER"E15431-004"
VALUE"22.0UF"
PACK_TYPE"0603V"
MATERIAL"X6S"
VOLTAGE"4V"
TOLERANCE"20%";
"B"
$PN"2"15;
"A"
$PN"1"14;
%"CAP_A"
"1","(-1000,-650)","0","dev_discrete","I232";
;
ROOM"PVDDQ_DEF"
CDS_SEC"1"
$SEC"1"
CDS_LOCATION"C5L10"
CDS_LIB"dev_discrete"
PART_NUMBER"E15431-004"
VOLTAGE"4V"
MATERIAL"X6S"
TOLERANCE"20%"
VALUE"22.0UF"
LOCATION"C5L10"
PACK_TYPE"0603V";
"B"
$PN"2"15;
"A"
$PN"1"14;
%"CAP_A"
"1","(-1275,-650)","0","dev_discrete","I233";
;
$SEC"1"
CDS_SEC"1"
ROOM"PVDDQ_DEF"
CDS_LIB"dev_discrete"
CDS_LOCATION"C5L9"
PART_NUMBER"E15431-004"
MATERIAL"X6S"
VOLTAGE"4V"
TOLERANCE"20%"
VALUE"22.0UF"
LOCATION"C5L9"
PACK_TYPE"0603V";
"B"
$PN"2"15;
"A"
$PN"1"14;
%"CAP_A"
"1","(-1550,-650)","0","dev_discrete","I234";
;
$SEC"1"
CDS_SEC"1"
ROOM"PVDDQ_DEF"
CDS_LOCATION"C5L8"
CDS_LIB"dev_discrete"
PART_NUMBER"E15431-004"
LOCATION"C5L8"
VALUE"22.0UF"
TOLERANCE"20%"
PACK_TYPE"0603V"
VOLTAGE"4V"
MATERIAL"X6S";
"B"
$PN"2"15;
"A"
$PN"1"14;
%"PVDDQ_DEF"
"1","(-2150,-400)","0","mstr_symbols","I235";
;
ROOM"VDDQ_DEF_PWR_VR"
BOM_COST"PROC_SOCKET "
HDL_POWER"PVDDQ_DEF"
CDS_LIB"mstr_symbols"
BODY_TYPE"PLUMBING"
VOLTAGE"1.2V";
"G\NAC"14;
%"CAP_A"
"1","(-1850,-650)","0","dev_discrete","I236";
;
$SEC"1"
CDS_SEC"1"
ROOM"PVDDQ_DEF"
CDS_LOCATION"C5L7"
CDS_LIB"dev_discrete"
PART_NUMBER"E15431-004"
LOCATION"C5L7"
VALUE"22.0UF"
TOLERANCE"20%"
PACK_TYPE"0603V"
MATERIAL"X6S"
VOLTAGE"4V";
"B"
$PN"2"15;
"A"
$PN"1"14;
%"CAP_A"
"1","(-2150,-650)","0","dev_discrete","I237";
;
ROOM"PVDDQ_DEF"
CDS_SEC"1"
$SEC"1"
CDS_LOCATION"C5L6"
CDS_LIB"dev_discrete"
LOCATION"C5L6"
PART_NUMBER"E15431-004"
VALUE"22.0UF"
TOLERANCE"20%"
PACK_TYPE"0603V"
VOLTAGE"4V"
MATERIAL"X6S";
"B"
$PN"2"15;
"A"
$PN"1"14;
%"GND"
"1","(-2150,-925)","0","mstr_symbols","I238";
;
HDL_POWER"GND"
VOLTAGE"0"
CDS_LIB"mstr_symbols"
SIZE"1B"
BODY_TYPE"PLUMBING"
BOM_COST"PROC_VRD_VCCIN_CPU0"
ROOM"VDDQ_ABC_PWR_VR";
"A\NAC"15;
%"SHUNT"
"1","(-300,2075)","0","mstr_misc","I239";
;
CDS_SEC"1"
CDS_LOCATION"SH4L2"
SEC_TYPE"SH0201"
SEC"1"
CDS_LIB"mstr_misc"
MATERIAL"EMPTY"
PACK_TYPE"SH0201"
PIN_SHORT"A:B"
LOCATION"SH4L2"
PART_NUMBER"N_A";
"A"
$PN"1"22;
"B"
$PN"2"17;
%"SHUNT"
"1","(-325,1625)","0","mstr_misc","I240";
;
CDS_SEC"1"
CDS_LOCATION"SH4L1"
SEC_TYPE"SH0201"
CDS_LIB"mstr_misc"
SEC"1"
MATERIAL"EMPTY"
PACK_TYPE"SH0201"
PIN_SHORT"A:B"
LOCATION"SH4L1"
PART_NUMBER"N_A";
"A"
$PN"1"23;
"B"
$PN"2"16;
%"RES"
"2","(4550,-175)","0","mstr_discrete","I58";
;
CDS_SEC"1"
$SEC"1"
ROOM"VDDQ_DEF_PWR_VR"
BOM_COST"MEM_VRD_PVPP_DEF"
CDS_LOCATION"R4L4"
CDS_LIB"mstr_discrete"
LOCATION"R4L4"
PART_NUMBER"G22026-003"
VALUE"120.0"
TOLERANCE"1%"
PACK_TYPE"0603"
MATERIAL"CHIP"
WATTAGE"1/10W";
"A"
$PN"1"18;
"B"
$PN"2"19;
%"GND"
"1","(-50,1400)","0","mstr_symbols","I65";
;
SIZE"1B"
HDL_POWER"GND"
VOLTAGE"0"
CDS_LIB"mstr_symbols"
BODY_TYPE"PLUMBING"
BOM_COST"MEM_VRD_PVPP_DEF"
ROOM"VDDQ_DEF_PWR_VR";
"A\NAC"16;
%"PVDDQ_DEF"
"1","(-25,2275)","0","mstr_symbols","I73";
;
ROOM"VDDQ_DEF_PWR_VR"
BOM_COST"MEM_VRD_PVPP_DEF"
HDL_POWER"PVDDQ_DEF"
CDS_LIB"mstr_symbols"
VOLTAGE"1.2V"
BODY_TYPE"PLUMBING";
"G\NAC"17;
%"RES"
"2","(-700,1825)","0","mstr_discrete","I74";
;
CDS_SEC"1"
SEC"1"
SEC_TYPE"0402"
ROOM"VDDQ_DEF_PWR_VR"
CDS_LOCATION"R4L2"
CDS_LIB"mstr_discrete"
PART_NUMBER"G21796-017"
VALUE"100.0"
LOCATION"R4L2"
TOLERANCE"1%"
WATTAGE"1/16W"
MATERIAL"EMPTY"
PACK_TYPE"0402";
"A"
$PN"1"22;
"B"
$PN"2"23;
%"CAPP"
"1","(2925,-150)","0","mstr_discrete","I75";
;
CDS_SEC"1"
SEC"1"
SEC_TYPE"3018"
ROOM"VDDQ_DEF_PWR_VR"
CDS_LOCATION"C3L6"
CDS_LIB"mstr_discrete"
LOCATION"C3L6"
PART_NUMBER"699013-049"
VALUE"470UF"
PACK_TYPE"3018"
VOLTAGE"2.5V"
MATERIAL"ALUM"
TOLERANCE"20%";
"B"
$PN"2"19;
"A"
$PN"1"18;
%"CAPP"
"1","(3350,-150)","0","mstr_discrete","I76";
;
CDS_SEC"1"
SEC"1"
SEC_TYPE"3018"
ROOM"VDDQ_DEF_PWR_VR"
CDS_LOCATION"C3L14"
CDS_LIB"mstr_discrete"
PART_NUMBER"699013-049"
LOCATION"C3L14"
VALUE"470UF"
TOLERANCE"20%"
VOLTAGE"2.5V"
MATERIAL"ALUM"
PACK_TYPE"3018";
"B"
$PN"2"19;
"A"
$PN"1"18;
%"CAPP"
"1","(3775,-150)","0","mstr_discrete","I77";
;
CDS_SEC"1"
SEC"1"
SEC_TYPE"3018"
ROOM"VDDQ_DEF_PWR_VR"
CDS_LOCATION"C6A5"
CDS_LIB"mstr_discrete"
PART_NUMBER"699013-049"
LOCATION"C6A5"
VALUE"470UF"
TOLERANCE"20%"
PACK_TYPE"3018"
VOLTAGE"2.5V"
MATERIAL"ALUM";
"B"
$PN"2"19;
"A"
$PN"1"18;
%"CAPP"
"1","(4175,-175)","0","mstr_discrete","I78";
;
CDS_SEC"1"
SEC_TYPE"3018"
SEC"1"
ROOM"VDDQ_DEF_PWR_VR"
CDS_LOCATION"C4L5"
CDS_LIB"mstr_discrete"
PART_NUMBER"699013-049"
VALUE"470UF"
LOCATION"C4L5"
TOLERANCE"20%"
VOLTAGE"2.5V"
MATERIAL"ALUM"
PACK_TYPE"3018";
"B"
$PN"2"19;
"A"
$PN"1"18;
%"PVDDQ_DEF"
"1","(2925,150)","0","mstr_symbols","I80";
;
ROOM"VDDQ_DEF_PWR_VR"
BOM_COST"MEM_VRD_PVPP_DEF"
HDL_POWER"PVDDQ_DEF"
CDS_LIB"mstr_symbols"
VOLTAGE"1.2V"
BODY_TYPE"PLUMBING";
"G\NAC"18;
%"GND"
"1","(2925,-575)","0","mstr_symbols","I81";
;
HDL_POWER"GND"
VOLTAGE"0"
SIZE"1B"
CDS_LIB"mstr_symbols"
BODY_TYPE"PLUMBING";
"A\NAC"19;
%"CAP"
"1","(5000,2825)","0","mstr_discrete","I82";
;
CDS_SEC"1"
ROOM"VDDQ_DEF_PWR_VR"
SEC"1"
BOM_COST"MEM_VRD_PVDDQ_DEF"
SEC_TYPE"0805"
CDS_LOCATION"C5M8"
CDS_LIB"mstr_discrete"
LOCATION"C5M8"
PART_NUMBER"602433-112"
VALUE"100UF"
TOLERANCE"20%"
PACK_TYPE"0805"
MATERIAL"X5R"
VOLTAGE"4V";
"A"
$PN"1"20;
"B"
$PN"2"21;
%"CAP"
"1","(4600,2825)","0","mstr_discrete","I83";
;
CDS_SEC"1"
ROOM"VDDQ_DEF_PWR_VR"
SEC_TYPE"0805"
BOM_COST"MEM_VRD_PVDDQ_DEF"
SEC"1"
CDS_LOCATION"C5L14"
CDS_LIB"mstr_discrete"
PART_NUMBER"602433-112"
LOCATION"C5L14"
VALUE"100UF"
TOLERANCE"20%"
PACK_TYPE"0805"
VOLTAGE"4V"
MATERIAL"X5R";
"A"
$PN"1"20;
"B"
$PN"2"21;
%"CAP"
"1","(4250,2825)","0","mstr_discrete","I88";
;
CDS_SEC"1"
ROOM"VDDQ_DEF_PWR_VR"
SEC_TYPE"0805"
SEC"1"
BOM_COST"MEM_VRD_PVDDQ_DEF"
CDS_LOCATION"C5M12"
CDS_LIB"mstr_discrete"
LOCATION"C5M12"
PART_NUMBER"602433-112"
VALUE"100UF"
TOLERANCE"20%"
PACK_TYPE"0805"
VOLTAGE"4V"
MATERIAL"X5R";
"A"
$PN"1"20;
"B"
$PN"2"21;
%"CAP"
"1","(3850,2825)","0","mstr_discrete","I89";
;
CDS_SEC"1"
ROOM"VDDQ_DEF_PWR_VR"
BOM_COST"MEM_VRD_PVDDQ_DEF"
SEC_TYPE"0805"
SEC"1"
CDS_LOCATION"C5L3"
CDS_LIB"mstr_discrete"
PART_NUMBER"602433-112"
VALUE"100UF"
LOCATION"C5L3"
VOLTAGE"4V"
MATERIAL"X5R"
PACK_TYPE"0805"
TOLERANCE"20%";
"A"
$PN"1"20;
"B"
$PN"2"21;
%"CAP"
"1","(3500,2825)","0","mstr_discrete","I90";
;
CDS_SEC"1"
ROOM"VDDQ_DEF_PWR_VR"
SEC"1"
SEC_TYPE"0805"
BOM_COST"MEM_VRD_PVDDQ_DEF"
CDS_LOCATION"C5L2"
CDS_LIB"mstr_discrete"
LOCATION"C5L2"
PART_NUMBER"602433-112"
VALUE"100UF"
TOLERANCE"20%"
PACK_TYPE"0805"
VOLTAGE"4V"
MATERIAL"X5R";
"A"
$PN"1"20;
"B"
$PN"2"21;
%"CAP"
"1","(3150,2825)","0","mstr_discrete","I91";
;
CDS_SEC"1"
CDS_LOCATION"C5L1"
SEC"1"
SEC_TYPE"0805"
BOM_COST"MEM_VRD_PVDDQ_DEF"
ROOM"VDDQ_DEF_PWR_VR"
CDS_LIB"mstr_discrete"
PART_NUMBER"602433-112"
VALUE"100UF"
LOCATION"C5L1"
VOLTAGE"4V"
MATERIAL"X5R"
PACK_TYPE"0805"
TOLERANCE"20%";
"A"
$PN"1"20;
"B"
$PN"2"21;
%"CAP"
"1","(2750,2825)","0","mstr_discrete","I92";
;
CDS_SEC"1"
ROOM"VDDQ_DEF_PWR_VR"
SEC"1"
SEC_TYPE"0805"
BOM_COST"MEM_VRD_PVDDQ_DEF"
CDS_LOCATION"C5A20"
CDS_LIB"mstr_discrete"
PART_NUMBER"602433-112"
LOCATION"C5A20"
VALUE"100UF"
TOLERANCE"20%"
PACK_TYPE"0805"
VOLTAGE"4V"
MATERIAL"X5R";
"A"
$PN"1"20;
"B"
$PN"2"21;
%"PVDDQ_DEF"
"1","(2400,3100)","0","mstr_symbols","I93";
;
HDL_POWER"PVDDQ_DEF"
ROOM"VDDQ_DEF_PWR_VR"
BOM_COST"MEM_VRD_PVDDQ_DEF"
CDS_LIB"mstr_symbols"
BODY_TYPE"PLUMBING"
VOLTAGE"1.2V";
"G\NAC"20;
%"GND"
"1","(4125,2450)","0","mstr_symbols","I94";
;
HDL_POWER"GND"
VOLTAGE"0"
SIZE"1B"
CDS_LIB"mstr_symbols"
BOM_COST"MEM_VRD_PVDDQ_DEF"
BODY_TYPE"PLUMBING"
ROOM"VDDQ_DEF_PWR_VR";
"A\NAC"21;
END.
